(kicad_pcb
	(version 20260206)
	(generator "pcbnew")
	(generator_version "10.0")
	(general
		(thickness 1.6)
		(legacy_teardrops no)
	)
	(paper "A4")
	(title_block
		(title "04192023_DAF0TMB3IC0_F0TG_MB_C_brd_V02_OCP.brd")
		(comment 1 "Grand Teton / footprints 5132-5136 of 8354")
	)
	(layers
		(0 "F.Cu" signal "TOP")
		(4 "In1.Cu" signal "GND")
		(6 "In2.Cu" signal "IN1")
		(8 "In3.Cu" signal "GND1")
		(10 "In4.Cu" signal "IN2")
		(12 "In5.Cu" signal "GND2")
		(14 "In6.Cu" signal "IN3")
		(16 "In7.Cu" signal "GND3")
		(18 "In8.Cu" signal "VCC")
		(20 "In9.Cu" signal "VCC1")
		(22 "In10.Cu" signal "GND4")
		(24 "In11.Cu" signal "IN4")
		(26 "In12.Cu" signal "GND5")
		(28 "In13.Cu" signal "IN5")
		(30 "In14.Cu" signal "GND6")
		(32 "In15.Cu" signal "IN6")
		(34 "In16.Cu" signal "GND7")
		(2 "B.Cu" signal "BOTTOM")
		(9 "F.Adhes" user "F.Adhesive")
		(11 "B.Adhes" user "B.Adhesive")
		(13 "F.Paste" user "Package Geometry/Pastemask Top")
		(15 "B.Paste" user "Package Geometry/Pastemask Bottom")
		(5 "F.SilkS" user "Ref Des/Silkscreen Top")
		(7 "B.SilkS" user "Ref Des/Silkscreen Bottom")
		(1 "F.Mask" user "Board Geometry/Soldermask Top")
		(3 "B.Mask" user "Board Geometry/Soldermask Bottom")
		(17 "Dwgs.User" user "User.Drawings")
		(19 "Cmts.User" user "User.Comments")
		(21 "Eco1.User" user "User.Eco1")
		(23 "Eco2.User" user "User.Eco2")
		(25 "Edge.Cuts" user "Board Geometry/Outline")
		(27 "Margin" user)
		(31 "F.CrtYd" user "Package Geometry/Place Bound Top")
		(29 "B.CrtYd" user "Package Geometry/Place Bound Bottom")
		(35 "F.Fab" user "Ref Des/Assembly Top")
		(33 "B.Fab" user "Ref Des/Assembly Bottom")
	)
	(footprint ""
		(layer "B.Cu")
		(at 300.538388 7.622794)
		(property "Reference" "J82"
			(at 4.445 1.171956 270)
			(unlocked yes)
			(layer "B.SilkS")
			(effects
				(font
					(size 0.7874 0.5842)
					(thickness 0.1524)
				)
				(justify left mirror)
			)
		)
		(property "Value" ""
			(at 0 0 0)
			(layer "B.Fab")
			(effects
				(font
					(size 1.27 1.27)
				)
				(justify mirror)
			)
		)
		(duplicate_pad_numbers_are_jumpers no)
		(fp_line
			(start -1.2192 -2.06756)
			(end -1.2192 2.06756)
			(stroke
				(width 0.1524)
				(type default)
			)
			(layer "B.SilkS")
		)
		(fp_line
			(start -1.2192 2.06756)
			(end 1.2192 2.06756)
			(stroke
				(width 0.1524)
				(type default)
			)
			(layer "B.SilkS")
		)
		(fp_line
			(start 1.2192 -2.06756)
			(end -1.2192 -2.06756)
			(stroke
				(width 0.1524)
				(type default)
			)
			(layer "B.SilkS")
		)
		(fp_line
			(start 1.2192 2.06756)
			(end 1.2192 -2.06756)
			(stroke
				(width 0.1524)
				(type default)
			)
			(layer "B.SilkS")
		)
		(pad "" np_thru_hole circle
			(at -3.4671 -1.27 270)
			(size 1.0414 1.0414)
			(drill 1.0414)
			(layers "*.Cu" "*.Mask")
			(clearance 0.381)
			(thermal_gap 0.381)
		)
		(pad "" np_thru_hole circle
			(at -3.4671 1.27 270)
			(size 1.0414 1.0414)
			(drill 1.0414)
			(layers "*.Cu" "*.Mask")
			(clearance 0.381)
			(thermal_gap 0.381)
		)
		(pad "" np_thru_hole circle
			(at 2.8829 -1.27 270)
			(size 1.0414 1.0414)
			(drill 1.0414)
			(layers "*.Cu" "*.Mask")
			(clearance 0.381)
			(thermal_gap 0.381)
		)
		(pad "" np_thru_hole circle
			(at 2.8829 1.27 270)
			(size 1.0414 1.0414)
			(drill 1.0414)
			(layers "*.Cu" "*.Mask")
			(clearance 0.381)
			(thermal_gap 0.381)
		)
		(pad "1" smd rect
			(at -0.8255 -0.249936 270)
			(size 0.3048 0.508)
			(layers "B.Cu" "B.Mask" "B.Paste")
			(net "DELTA_L_85_10INCH_BOT_DN")
		)
		(pad "2" smd rect
			(at -0.8255 0.249936 270)
			(size 0.3048 0.508)
			(layers "B.Cu" "B.Mask" "B.Paste")
			(net "DELTA_L_85_10INCH_BOT_DP")
		)
		(pad "3" smd circle
			(at 0 0 180)
			(size 0 0)
			(layers "B.Cu" "B.Mask" "B.Paste")
			(net "DELTA_L_GND_1")
		)
		(zone
			(layers "F.Cu" "B.Cu" "In1.Cu" "In2.Cu" "In3.Cu" "In4.Cu" "In5.Cu" "In6.Cu"
				"In7.Cu" "In8.Cu" "In9.Cu" "In10.Cu" "In11.Cu" "In12.Cu" "In13.Cu" "In14.Cu"
				"In15.Cu" "In16.Cu"
			)
			(hatch none 0.5)
			(connect_pads
				(clearance 0)
			)
			(min_thickness 0.25)
			(keepout
				(tracks not_allowed)
				(vias allowed)
				(pads allowed)
				(copperpour not_allowed)
				(footprints allowed)
			)
			(placement
				(enabled no)
				(sheetname "")
			)
			(fill
				(thermal_gap 0.5)
				(thermal_bridge_width 0.5)
				(island_removal_mode 0)
			)
			(polygon
				(pts
					(arc
						(start 297.998388 6.352794)
						(mid 296.144188 6.352794)
						(end 297.998388 6.352794)
					)
				)
			)
		)
		(zone
			(layers "F.Cu" "B.Cu" "In1.Cu" "In2.Cu" "In3.Cu" "In4.Cu" "In5.Cu" "In6.Cu"
				"In7.Cu" "In8.Cu" "In9.Cu" "In10.Cu" "In11.Cu" "In12.Cu" "In13.Cu" "In14.Cu"
				"In15.Cu" "In16.Cu"
			)
			(hatch none 0.5)
			(connect_pads
				(clearance 0)
			)
			(min_thickness 0.25)
			(keepout
				(tracks not_allowed)
				(vias allowed)
				(pads allowed)
				(copperpour not_allowed)
				(footprints allowed)
			)
			(placement
				(enabled no)
				(sheetname "")
			)
			(fill
				(thermal_gap 0.5)
				(thermal_bridge_width 0.5)
				(island_removal_mode 0)
			)
			(polygon
				(pts
					(arc
						(start 297.998388 8.892794)
						(mid 296.144188 8.892794)
						(end 297.998388 8.892794)
					)
				)
			)
		)
		(zone
			(layers "F.Cu" "B.Cu" "In1.Cu" "In2.Cu" "In3.Cu" "In4.Cu" "In5.Cu" "In6.Cu"
				"In7.Cu" "In8.Cu" "In9.Cu" "In10.Cu" "In11.Cu" "In12.Cu" "In13.Cu" "In14.Cu"
				"In15.Cu" "In16.Cu"
			)
			(hatch none 0.5)
			(connect_pads
				(clearance 0)
			)
			(min_thickness 0.25)
			(keepout
				(tracks not_allowed)
				(vias allowed)
				(pads allowed)
				(copperpour not_allowed)
				(footprints allowed)
			)
			(placement
				(enabled no)
				(sheetname "")
			)
			(fill
				(thermal_gap 0.5)
				(thermal_bridge_width 0.5)
				(island_removal_mode 0)
			)
			(polygon
				(pts
					(arc
						(start 304.348388 6.352794)
						(mid 302.494188 6.352794)
						(end 304.348388 6.352794)
					)
				)
			)
		)
		(zone
			(layers "F.Cu" "B.Cu" "In1.Cu" "In2.Cu" "In3.Cu" "In4.Cu" "In5.Cu" "In6.Cu"
				"In7.Cu" "In8.Cu" "In9.Cu" "In10.Cu" "In11.Cu" "In12.Cu" "In13.Cu" "In14.Cu"
				"In15.Cu" "In16.Cu"
			)
			(hatch none 0.5)
			(connect_pads
				(clearance 0)
			)
			(min_thickness 0.25)
			(keepout
				(tracks not_allowed)
				(vias allowed)
				(pads allowed)
				(copperpour not_allowed)
				(footprints allowed)
			)
			(placement
				(enabled no)
				(sheetname "")
			)
			(fill
				(thermal_gap 0.5)
				(thermal_bridge_width 0.5)
				(island_removal_mode 0)
			)
			(polygon
				(pts
					(arc
						(start 304.348388 8.892794)
						(mid 302.494188 8.892794)
						(end 304.348388 8.892794)
					)
				)
			)
		)
		(zone
			(layer "B.Cu")
			(hatch none 0.5)
			(connect_pads
				(clearance 0)
			)
			(min_thickness 0.25)
			(keepout
				(tracks not_allowed)
				(vias allowed)
				(pads allowed)
				(copperpour not_allowed)
				(footprints allowed)
			)
			(placement
				(enabled no)
				(sheetname "")
			)
			(fill
				(thermal_gap 0.5)
				(thermal_bridge_width 0.5)
				(island_removal_mode 0)
			)
			(polygon
				(pts
					(xy 299.420788 7.074154) (xy 299.420788 7.169658) (xy 300.017688 7.169658) (xy 300.017688 7.576058)
					(xy 299.420788 7.576058) (xy 299.420788 7.66953) (xy 300.017688 7.66953) (xy 300.017688 8.07593)
					(xy 299.420788 8.07593) (xy 299.420788 8.171434) (xy 300.119288 8.171434) (xy 300.119288 7.074154)
				)
			)
		)
	)
	(footprint ""
		(layer "B.Cu")
		(at 51.72964 -424.225212 90)
		(property "Reference" "C1756"
			(at 0 0 90)
			(layer "B.SilkS")
			(hide yes)
			(effects
				(font
					(size 1.27 1.27)
				)
				(justify mirror)
			)
		)
		(property "Value" ""
			(at 0 0 90)
			(layer "B.Fab")
			(effects
				(font
					(size 1.27 1.27)
				)
				(justify mirror)
			)
		)
		(duplicate_pad_numbers_are_jumpers no)
		(fp_line
			(start 0.7874 -0.4064)
			(end -0.7874 -0.4064)
			(stroke
				(width 0.1524)
				(type default)
			)
			(layer "B.SilkS")
		)
		(fp_line
			(start -0.7874 -0.4064)
			(end -0.7874 0.4064)
			(stroke
				(width 0.1524)
				(type default)
			)
			(layer "B.SilkS")
		)
		(fp_line
			(start 0.7874 0.4064)
			(end 0.7874 -0.4064)
			(stroke
				(width 0.1524)
				(type default)
			)
			(layer "B.SilkS")
		)
		(fp_line
			(start -0.7874 0.4064)
			(end 0.7874 0.4064)
			(stroke
				(width 0.1524)
				(type default)
			)
			(layer "B.SilkS")
		)
		(fp_line
			(start 0.67945 -0.305054)
			(end 0.12065 -0.305054)
			(stroke
				(width 0.1)
				(type default)
			)
			(layer "B.Fab")
		)
		(fp_line
			(start 0.12065 -0.305054)
			(end 0.12065 -0.2794)
			(stroke
				(width 0.1)
				(type default)
			)
			(layer "B.Fab")
		)
		(fp_line
			(start -0.12065 -0.3048)
			(end -0.67945 -0.3048)
			(stroke
				(width 0.1)
				(type default)
			)
			(layer "B.Fab")
		)
		(fp_line
			(start -0.67945 -0.3048)
			(end -0.67945 0.3048)
			(stroke
				(width 0.1)
				(type default)
			)
			(layer "B.Fab")
		)
		(fp_line
			(start 0.12065 -0.2794)
			(end -0.12065 -0.2794)
			(stroke
				(width 0.1)
				(type default)
			)
			(layer "B.Fab")
		)
		(fp_line
			(start -0.12065 -0.2794)
			(end -0.12065 -0.3048)
			(stroke
				(width 0.1)
				(type default)
			)
			(layer "B.Fab")
		)
		(fp_line
			(start 0.12065 0.2794)
			(end 0.12065 0.3048)
			(stroke
				(width 0.1)
				(type default)
			)
			(layer "B.Fab")
		)
		(fp_line
			(start -0.120396 0.2794)
			(end 0.12065 0.2794)
			(stroke
				(width 0.1)
				(type default)
			)
			(layer "B.Fab")
		)
		(fp_line
			(start 0.67945 0.3048)
			(end 0.67945 -0.305054)
			(stroke
				(width 0.1)
				(type default)
			)
			(layer "B.Fab")
		)
		(fp_line
			(start 0.12065 0.3048)
			(end 0.67945 0.3048)
			(stroke
				(width 0.1)
				(type default)
			)
			(layer "B.Fab")
		)
		(fp_line
			(start -0.120396 0.3048)
			(end -0.120396 0.2794)
			(stroke
				(width 0.1)
				(type default)
			)
			(layer "B.Fab")
		)
		(fp_line
			(start -0.67945 0.3048)
			(end -0.120396 0.3048)
			(stroke
				(width 0.1)
				(type default)
			)
			(layer "B.Fab")
		)
		(pad "1" smd circle
			(at 0.40005 0 270)
			(size 0 0)
			(layers "B.Cu" "B.Mask" "B.Paste")
			(net "FM_GPU_PWRGD_ISO")
		)
		(pad "2" smd circle
			(at -0.40005 0 270)
			(size 0 0)
			(layers "B.Cu" "B.Mask" "B.Paste")
			(net "GND")
		)
	)
	(footprint ""
		(layer "B.Cu")
		(at 370.491004 -398.942052 90)
		(property "Reference" "C1037"
			(at 0 0 90)
			(layer "B.SilkS")
			(hide yes)
			(effects
				(font
					(size 1.27 1.27)
				)
				(justify mirror)
			)
		)
		(property "Value" ""
			(at 0 0 90)
			(layer "B.Fab")
			(effects
				(font
					(size 1.27 1.27)
				)
				(justify mirror)
			)
		)
		(duplicate_pad_numbers_are_jumpers no)
		(fp_line
			(start 0.7874 -0.4064)
			(end -0.7874 -0.4064)
			(stroke
				(width 0.1524)
				(type default)
			)
			(layer "B.SilkS")
		)
		(fp_line
			(start -0.7874 -0.4064)
			(end -0.7874 0.4064)
			(stroke
				(width 0.1524)
				(type default)
			)
			(layer "B.SilkS")
		)
		(fp_line
			(start 0.7874 0.4064)
			(end 0.7874 -0.4064)
			(stroke
				(width 0.1524)
				(type default)
			)
			(layer "B.SilkS")
		)
		(fp_line
			(start -0.7874 0.4064)
			(end 0.7874 0.4064)
			(stroke
				(width 0.1524)
				(type default)
			)
			(layer "B.SilkS")
		)
		(fp_line
			(start 0.67945 -0.305054)
			(end 0.12065 -0.305054)
			(stroke
				(width 0.1)
				(type default)
			)
			(layer "B.Fab")
		)
		(fp_line
			(start 0.12065 -0.305054)
			(end 0.12065 -0.2794)
			(stroke
				(width 0.1)
				(type default)
			)
			(layer "B.Fab")
		)
		(fp_line
			(start -0.12065 -0.3048)
			(end -0.67945 -0.3048)
			(stroke
				(width 0.1)
				(type default)
			)
			(layer "B.Fab")
		)
		(fp_line
			(start -0.67945 -0.3048)
			(end -0.67945 0.3048)
			(stroke
				(width 0.1)
				(type default)
			)
			(layer "B.Fab")
		)
		(fp_line
			(start 0.12065 -0.2794)
			(end -0.12065 -0.2794)
			(stroke
				(width 0.1)
				(type default)
			)
			(layer "B.Fab")
		)
		(fp_line
			(start -0.12065 -0.2794)
			(end -0.12065 -0.3048)
			(stroke
				(width 0.1)
				(type default)
			)
			(layer "B.Fab")
		)
		(fp_line
			(start 0.12065 0.2794)
			(end 0.12065 0.3048)
			(stroke
				(width 0.1)
				(type default)
			)
			(layer "B.Fab")
		)
		(fp_line
			(start -0.120396 0.2794)
			(end 0.12065 0.2794)
			(stroke
				(width 0.1)
				(type default)
			)
			(layer "B.Fab")
		)
		(fp_line
			(start 0.67945 0.3048)
			(end 0.67945 -0.305054)
			(stroke
				(width 0.1)
				(type default)
			)
			(layer "B.Fab")
		)
		(fp_line
			(start 0.12065 0.3048)
			(end 0.67945 0.3048)
			(stroke
				(width 0.1)
				(type default)
			)
			(layer "B.Fab")
		)
		(fp_line
			(start -0.120396 0.3048)
			(end -0.120396 0.2794)
			(stroke
				(width 0.1)
				(type default)
			)
			(layer "B.Fab")
		)
		(fp_line
			(start -0.67945 0.3048)
			(end -0.120396 0.3048)
			(stroke
				(width 0.1)
				(type default)
			)
			(layer "B.Fab")
		)
		(pad "1" smd circle
			(at 0.40005 0 270)
			(size 0 0)
			(layers "B.Cu" "B.Mask" "B.Paste")
			(net "P0V9_CPU0_RT3_2A")
		)
		(pad "2" smd circle
			(at -0.40005 0 270)
			(size 0 0)
			(layers "B.Cu" "B.Mask" "B.Paste")
			(net "GND")
		)
	)
	(footprint ""
		(layer "B.Cu")
		(at 352.425 -177.912522 90)
		(property "Reference" "PC576_5"
			(at 0 0 90)
			(layer "B.SilkS")
			(hide yes)
			(effects
				(font
					(size 1.27 1.27)
				)
				(justify mirror)
			)
		)
		(property "Value" ""
			(at 0 0 90)
			(layer "B.Fab")
			(effects
				(font
					(size 1.27 1.27)
				)
				(justify mirror)
			)
		)
		(duplicate_pad_numbers_are_jumpers no)
		(fp_line
			(start 1.524 -0.762)
			(end -1.524 -0.762)
			(stroke
				(width 0.1524)
				(type default)
			)
			(layer "B.SilkS")
		)
		(fp_line
			(start -1.524 -0.762)
			(end -1.524 0.762)
			(stroke
				(width 0.1524)
				(type default)
			)
			(layer "B.SilkS")
		)
		(fp_line
			(start 1.524 0.762)
			(end 1.524 -0.762)
			(stroke
				(width 0.1524)
				(type default)
			)
			(layer "B.SilkS")
		)
		(fp_line
			(start -1.524 0.762)
			(end 1.524 0.762)
			(stroke
				(width 0.1524)
				(type default)
			)
			(layer "B.SilkS")
		)
		(fp_line
			(start 1.1049 -0.724916)
			(end 1.1049 0.724916)
			(stroke
				(width 0.1)
				(type default)
			)
			(layer "B.Fab")
		)
		(fp_line
			(start -1.1049 -0.724916)
			(end 1.1049 -0.724916)
			(stroke
				(width 0.1)
				(type default)
			)
			(layer "B.Fab")
		)
		(fp_line
			(start 1.1049 0.724916)
			(end -1.1049 0.724916)
			(stroke
				(width 0.1)
				(type default)
			)
			(layer "B.Fab")
		)
		(fp_line
			(start -1.1049 0.724916)
			(end -1.1049 -0.724916)
			(stroke
				(width 0.1)
				(type default)
			)
			(layer "B.Fab")
		)
		(pad "1" smd rect
			(at 0.889 0 90)
			(size 1.016 1.27)
			(layers "B.Cu" "B.Mask" "B.Paste")
			(net "PVDDCR_CPU0_P0")
		)
		(pad "2" smd rect
			(at -0.889 0 90)
			(size 1.016 1.27)
			(layers "B.Cu" "B.Mask" "B.Paste")
			(net "GND")
		)
	)
	(footprint ""
		(layer "B.Cu")
		(at 355.041454 -248.47931 180)
		(property "Reference" "C263"
			(at 0 0 0)
			(layer "B.SilkS")
			(hide yes)
			(effects
				(font
					(size 1.27 1.27)
				)
				(justify mirror)
			)
		)
		(property "Value" ""
			(at 0 0 0)
			(layer "B.Fab")
			(effects
				(font
					(size 1.27 1.27)
				)
				(justify mirror)
			)
		)
		(duplicate_pad_numbers_are_jumpers no)
		(fp_line
			(start 0.7874 0.4064)
			(end 0.7874 -0.4064)
			(stroke
				(width 0.1524)
				(type default)
			)
			(layer "B.SilkS")
		)
		(fp_line
			(start 0.7874 -0.4064)
			(end -0.7874 -0.4064)
			(stroke
				(width 0.1524)
				(type default)
			)
			(layer "B.SilkS")
		)
		(fp_line
			(start -0.7874 0.4064)
			(end 0.7874 0.4064)
			(stroke
				(width 0.1524)
				(type default)
			)
			(layer "B.SilkS")
		)
		(fp_line
			(start -0.7874 -0.4064)
			(end -0.7874 0.4064)
			(stroke
				(width 0.1524)
				(type default)
			)
			(layer "B.SilkS")
		)
		(fp_line
			(start 0.67945 0.3048)
			(end 0.67945 -0.305054)
			(stroke
				(width 0.1)
				(type default)
			)
			(layer "B.Fab")
		)
		(fp_line
			(start 0.67945 -0.305054)
			(end 0.12065 -0.305054)
			(stroke
				(width 0.1)
				(type default)
			)
			(layer "B.Fab")
		)
		(fp_line
			(start 0.12065 0.3048)
			(end 0.67945 0.3048)
			(stroke
				(width 0.1)
				(type default)
			)
			(layer "B.Fab")
		)
		(fp_line
			(start 0.12065 0.2794)
			(end 0.12065 0.3048)
			(stroke
				(width 0.1)
				(type default)
			)
			(layer "B.Fab")
		)
		(fp_line
			(start 0.12065 -0.2794)
			(end -0.12065 -0.2794)
			(stroke
				(width 0.1)
				(type default)
			)
			(layer "B.Fab")
		)
		(fp_line
			(start 0.12065 -0.305054)
			(end 0.12065 -0.2794)
			(stroke
				(width 0.1)
				(type default)
			)
			(layer "B.Fab")
		)
		(fp_line
			(start -0.120396 0.3048)
			(end -0.120396 0.2794)
			(stroke
				(width 0.1)
				(type default)
			)
			(layer "B.Fab")
		)
		(fp_line
			(start -0.120396 0.2794)
			(end 0.12065 0.2794)
			(stroke
				(width 0.1)
				(type default)
			)
			(layer "B.Fab")
		)
		(fp_line
			(start -0.12065 -0.2794)
			(end -0.12065 -0.3048)
			(stroke
				(width 0.1)
				(type default)
			)
			(layer "B.Fab")
		)
		(fp_line
			(start -0.12065 -0.3048)
			(end -0.67945 -0.3048)
			(stroke
				(width 0.1)
				(type default)
			)
			(layer "B.Fab")
		)
		(fp_line
			(start -0.67945 0.3048)
			(end -0.120396 0.3048)
			(stroke
				(width 0.1)
				(type default)
			)
			(layer "B.Fab")
		)
		(fp_line
			(start -0.67945 -0.3048)
			(end -0.67945 0.3048)
			(stroke
				(width 0.1)
				(type default)
			)
			(layer "B.Fab")
		)
		(pad "1" smd circle
			(at 0.40005 0)
			(size 0 0)
			(layers "B.Cu" "B.Mask" "B.Paste")
			(net "PVDDCR_CPU0_P0")
		)
		(pad "2" smd circle
			(at -0.40005 0)
			(size 0 0)
			(layers "B.Cu" "B.Mask" "B.Paste")
			(net "GND")
		)
	)
)
